(kicad_pcb
	(version 20241229)
	(generator "pcbnew")
	(generator_version "9.0")
	(general
		(thickness 1.711)
		(legacy_teardrops no)
	)
	(paper "A4")
	(title_block
		(title "Antmicro Baseboard for Jetson AGX Thor")
		(date "2026-02-18")
		(rev "1.1.0")
		(company "Antmicro Ltd")
		(comment 1 "www.antmicro.com")
		(comment 9 "footprints 386-389 of 1170")
	)
	(layers
		(0 "F.Cu" signal)
		(4 "In1.Cu" signal)
		(6 "In2.Cu" signal)
		(8 "In3.Cu" signal)
		(10 "In4.Cu" jumper)
		(12 "In5.Cu" signal)
		(14 "In6.Cu" signal)
		(16 "In7.Cu" signal)
		(18 "In8.Cu" signal)
		(2 "B.Cu" signal)
		(9 "F.Adhes" user "F.Adhesive")
		(11 "B.Adhes" user "B.Adhesive")
		(13 "F.Paste" user)
		(15 "B.Paste" user)
		(5 "F.SilkS" user "F.Silkscreen")
		(7 "B.SilkS" user "B.Silkscreen")
		(1 "F.Mask" user)
		(3 "B.Mask" user)
		(17 "Dwgs.User" user "User.Drawings")
		(19 "Cmts.User" user "User.Comments")
		(21 "Eco1.User" user "User.Eco1")
		(23 "Eco2.User" user "User.Eco2")
		(25 "Edge.Cuts" user)
		(27 "Margin" user)
		(31 "F.CrtYd" user "F.Courtyard")
		(29 "B.CrtYd" user "B.Courtyard")
		(35 "F.Fab" user)
		(33 "B.Fab" user)
	)
	(footprint "antmicro-footprints:C_0402_1005Metric"
		(layer "F.Cu")
		(at 139.4 104.8 -90)
		(descr "Capacitor SMD 0402")
		(tags "capacitor SMD 0402")
		(property "Reference" "C313"
			(at -3.8 0.4 90)
			(layer "F.SilkS")
			(effects
				(font
					(size 0.7 0.7)
					(thickness 0.15)
				)
				(justify right top)
			)
		)
		(property "Value" "C_100n_0402"
			(at -1.022927 2.155213 90)
			(layer "F.Fab")
			(effects
				(font
					(size 0.7 0.7)
					(thickness 0.15)
				)
				(justify right top)
			)
		)
		(property "Datasheet" "https://www.murata.com/products/productdetail?partno=GRM155R61H104KE14%23"
			(at 0 0 90)
			(layer "F.Fab")
			(hide yes)
			(effects
				(font
					(size 1.27 1.27)
					(thickness 0.15)
				)
			)
		)
		(property "Description" "SMD Multilayer Ceramic Capacitor, 0.1 µF, 50 V, 0402 [1005 Metric], ± 10%, X5R, GRM Series"
			(at 0 0 90)
			(layer "F.Fab")
			(hide yes)
			(effects
				(font
					(size 1.27 1.27)
					(thickness 0.15)
				)
			)
		)
		(property "Manufacturer" "Murata"
			(at 0 0 270)
			(unlocked yes)
			(layer "F.Fab")
			(hide yes)
			(effects
				(font
					(size 1 1)
					(thickness 0.15)
				)
			)
		)
		(property "MPN" "GRM155R61H104KE14D"
			(at 0 0 270)
			(unlocked yes)
			(layer "F.Fab")
			(hide yes)
			(effects
				(font
					(size 1 1)
					(thickness 0.15)
				)
			)
		)
		(property "Val" "100n"
			(at 0 0 270)
			(unlocked yes)
			(layer "F.Fab")
			(hide yes)
			(effects
				(font
					(size 1 1)
					(thickness 0.15)
				)
			)
		)
		(property "License" "Apache-2.0"
			(at 0 0 270)
			(unlocked yes)
			(layer "F.Fab")
			(hide yes)
			(effects
				(font
					(size 1 1)
					(thickness 0.15)
				)
			)
		)
		(property "Author" "Antmicro"
			(at 0 0 270)
			(unlocked yes)
			(layer "F.Fab")
			(hide yes)
			(effects
				(font
					(size 1 1)
					(thickness 0.15)
				)
			)
		)
		(property "Voltage" "50V"
			(at 0 0 270)
			(unlocked yes)
			(layer "F.Fab")
			(hide yes)
			(effects
				(font
					(size 1 1)
					(thickness 0.15)
				)
			)
		)
		(property "Dielectric" "X5R"
			(at 0 0 270)
			(unlocked yes)
			(layer "F.Fab")
			(hide yes)
			(effects
				(font
					(size 1 1)
					(thickness 0.15)
				)
			)
		)
		(sheetname "/Peripherals/")
		(sheetfile "peripherals.kicad_sch")
		(attr smd)
		(fp_rect
			(start -0.925 -0.47)
			(end 0.925 0.47)
			(stroke
				(width 0.05)
				(type default)
			)
			(fill no)
			(layer "F.CrtYd")
		)
		(fp_line
			(start -0.494 0.248)
			(end -0.494 -0.25)
			(stroke
				(width 0.15)
				(type solid)
			)
			(layer "F.Fab")
		)
		(fp_line
			(start 0.504 0.248)
			(end -0.494 0.248)
			(stroke
				(width 0.15)
				(type solid)
			)
			(layer "F.Fab")
		)
		(fp_line
			(start -0.494 -0.25)
			(end 0.504 -0.25)
			(stroke
				(width 0.15)
				(type solid)
			)
			(layer "F.Fab")
		)
		(fp_line
			(start 0.504 -0.25)
			(end 0.504 0.248)
			(stroke
				(width 0.15)
				(type solid)
			)
			(layer "F.Fab")
		)
		(fp_text user "License: Apache-2.0"
			(at -0.939 5.799 90)
			(layer "F.Fab")
			(effects
				(font
					(size 0.7 0.7)
					(thickness 0.15)
				)
				(justify right top)
			)
		)
		(fp_text user "Author: Antmicro"
			(at -0.939 3.399 90)
			(layer "F.Fab")
			(effects
				(font
					(size 0.7 0.7)
					(thickness 0.15)
				)
				(justify right top)
			)
		)
		(fp_text user "${REFERENCE}"
			(at -0.939 4.599 90)
			(layer "F.Fab")
			(effects
				(font
					(size 0.7 0.7)
					(thickness 0.15)
				)
				(justify right top)
			)
		)
		(pad "1" smd roundrect
			(at -0.48 0 270)
			(size 0.59 0.64)
			(layers "F.Cu" "F.Mask" "F.Paste")
			(roundrect_rratio 0.25)
			(net 1 "GND")
			(pintype "passive")
		)
		(pad "2" smd roundrect
			(at 0.48 0 270)
			(size 0.59 0.64)
			(layers "F.Cu" "F.Mask" "F.Paste")
			(roundrect_rratio 0.25)
			(net 2 "+3V3")
			(pintype "passive")
		)
	)
	(footprint "antmicro-footprints:R_0402_1005Metric"
		(layer "F.Cu")
		(at 142.06 58.8 -90)
		(descr "Resistor SMD 0402")
		(tags "resistor SMD 0402")
		(property "Reference" "R417"
			(at 1.01 0.27 90)
			(layer "F.SilkS")
			(effects
				(font
					(size 0.7 0.7)
					(thickness 0.15)
				)
				(justify right top)
			)
		)
		(property "Value" "R_10k_0402"
			(at -1.011843 1.772046 90)
			(layer "F.Fab")
			(effects
				(font
					(size 0.7 0.7)
					(thickness 0.15)
				)
				(justify right top)
			)
		)
		(property "Datasheet" "https://www.bourns.com/docs/product-datasheets/cr.pdf"
			(at 0 0 90)
			(layer "F.Fab")
			(hide yes)
			(effects
				(font
					(size 1.27 1.27)
					(thickness 0.15)
				)
			)
		)
		(property "Description" "SMD Chip Resistor, 10 kohm, ± 1%, 62.5 mW, 0402 [1005 Metric], Thick Film, General Purpose"
			(at 0 0 90)
			(layer "F.Fab")
			(hide yes)
			(effects
				(font
					(size 1.27 1.27)
					(thickness 0.15)
				)
			)
		)
		(property "MPN" "CR0402-FX-1002GLF"
			(at 0 0 270)
			(unlocked yes)
			(layer "F.Fab")
			(hide yes)
			(effects
				(font
					(size 1 1)
					(thickness 0.15)
				)
			)
		)
		(property "Manufacturer" "Bourns"
			(at 0 0 270)
			(unlocked yes)
			(layer "F.Fab")
			(hide yes)
			(effects
				(font
					(size 1 1)
					(thickness 0.15)
				)
			)
		)
		(property "License" "Apache-2.0"
			(at 0 0 270)
			(unlocked yes)
			(layer "F.Fab")
			(hide yes)
			(effects
				(font
					(size 1 1)
					(thickness 0.15)
				)
			)
		)
		(property "Author" "Antmicro"
			(at 0 0 270)
			(unlocked yes)
			(layer "F.Fab")
			(hide yes)
			(effects
				(font
					(size 1 1)
					(thickness 0.15)
				)
			)
		)
		(property "Val" "10k"
			(at 0 0 270)
			(unlocked yes)
			(layer "F.Fab")
			(hide yes)
			(effects
				(font
					(size 1 1)
					(thickness 0.15)
				)
			)
		)
		(property "Tolerance" "1%"
			(at 0 0 270)
			(unlocked yes)
			(layer "F.Fab")
			(hide yes)
			(effects
				(font
					(size 1 1)
					(thickness 0.15)
				)
			)
		)
		(sheetname "/Power/")
		(sheetfile "power.kicad_sch")
		(attr smd)
		(fp_poly
			(pts
				(xy -0.925 -0.47) (xy 0.925 -0.47) (xy 0.925 0.47) (xy -0.925 0.47)
			)
			(stroke
				(width 0.05)
				(type default)
			)
			(fill no)
			(layer "F.CrtYd")
		)
		(fp_poly
			(pts
				(xy -0.5 -0.25) (xy 0.5 -0.25) (xy 0.5 0.25) (xy -0.5 0.25)
			)
			(stroke
				(width 0.15)
				(type solid)
			)
			(fill no)
			(layer "F.Fab")
		)
		(fp_text user "License: Apache-2.0"
			(at -0.949999 5.169 90)
			(layer "F.Fab")
			(effects
				(font
					(size 0.7 0.7)
					(thickness 0.15)
				)
				(justify right top)
			)
		)
		(fp_text user "Author: Antmicro"
			(at -0.95 4.169 90)
			(layer "F.Fab")
			(effects
				(font
					(size 0.7 0.7)
					(thickness 0.15)
				)
				(justify right top)
			)
		)
		(fp_text user "${REFERENCE}"
			(at -0.95 3.168 90)
			(layer "F.Fab")
			(effects
				(font
					(size 0.7 0.7)
					(thickness 0.15)
				)
				(justify right top)
			)
		)
		(pad "1" smd roundrect
			(at -0.48 0 270)
			(size 0.59 0.64)
			(layers "F.Cu" "F.Mask" "F.Paste")
			(roundrect_rratio 0.25)
			(net 1 "GND")
			(pintype "passive")
		)
		(pad "2" smd roundrect
			(at 0.48 0 270)
			(size 0.59 0.64)
			(layers "F.Cu" "F.Mask" "F.Paste")
			(roundrect_rratio 0.25)
			(net 1396 "Net-(U79-ADJ)")
			(pintype "passive")
		)
	)
	(footprint "antmicro-footprints:TDFN-6-1EP_3x3mm_P0.95mm"
		(layer "F.Cu")
		(at 210.4 64.9 -90)
		(property "Reference" "U9"
			(at -2.09 0.75 0)
			(layer "F.SilkS")
			(effects
				(font
					(size 0.7 0.7)
					(thickness 0.15)
				)
				(justify left bottom)
			)
		)
		(property "Value" "MAX16013"
			(at -2 4.1 270)
			(layer "F.Fab")
			(effects
				(font
					(size 0.7 0.7)
					(thickness 0.15)
				)
				(justify left bottom)
			)
		)
		(property "Datasheet" "https://www.analog.com/media/en/technical-documentation/data-sheets/max16010-max16014.pdf"
			(at 0 0 270)
			(layer "F.Fab")
			(effects
				(font
					(size 0.7 0.7)
					(thickness 0.15)
				)
				(justify left bottom)
			)
		)
		(property "Description" "Over voltage, reverse voltage protection"
			(at 0 0 270)
			(layer "F.Fab")
			(effects
				(font
					(size 0.7 0.7)
					(thickness 0.15)
				)
				(justify left bottom)
			)
		)
		(property "Manufacturer" "Analog Devices"
			(at 0 0 270)
			(unlocked yes)
			(layer "F.Fab")
			(hide yes)
			(effects
				(font
					(size 1 1)
					(thickness 0.15)
				)
			)
		)
		(property "MPN" "MAX16013TT-T"
			(at 0 0 270)
			(unlocked yes)
			(layer "F.Fab")
			(hide yes)
			(effects
				(font
					(size 1 1)
					(thickness 0.15)
				)
			)
		)
		(property "Author" "Antmicro"
			(at 0 0 270)
			(unlocked yes)
			(layer "F.Fab")
			(hide yes)
			(effects
				(font
					(size 1 1)
					(thickness 0.15)
				)
			)
		)
		(property "License" "Apache-2.0"
			(at 0 0 270)
			(unlocked yes)
			(layer "F.Fab")
			(hide yes)
			(effects
				(font
					(size 1 1)
					(thickness 0.15)
				)
			)
		)
		(sheetname "/Power/")
		(sheetfile "power.kicad_sch")
		(attr smd)
		(fp_line
			(start -1.55 1.55)
			(end 1.55 1.55)
			(stroke
				(width 0.15)
				(type solid)
			)
			(layer "F.SilkS")
		)
		(fp_line
			(start -1.55 -1.55)
			(end 1.55 -1.55)
			(stroke
				(width 0.15)
				(type solid)
			)
			(layer "F.SilkS")
		)
		(fp_circle
			(center -1.85 -1.4)
			(end -1.8 -1.4)
			(stroke
				(width 0.15)
				(type solid)
			)
			(fill yes)
			(layer "F.SilkS")
		)
		(fp_poly
			(pts
				(xy -0.47 -0.73) (xy 0.47 -0.73) (xy 0.47 0.73) (xy -0.47 0.73)
			)
			(stroke
				(width 0.01)
				(type solid)
			)
			(fill yes)
			(layer "F.Paste")
		)
		(fp_rect
			(start -2.12 -1.75)
			(end 2.12 1.75)
			(stroke
				(width 0.05)
				(type solid)
			)
			(fill no)
			(layer "F.CrtYd")
		)
		(fp_line
			(start -1.55 1.55)
			(end 1.55 1.55)
			(stroke
				(width 0.15)
				(type solid)
			)
			(layer "F.Fab")
		)
		(fp_line
			(start -1.55 -1.55)
			(end -1.55 1.55)
			(stroke
				(width 0.15)
				(type solid)
			)
			(layer "F.Fab")
		)
		(fp_line
			(start -1.55 -1.55)
			(end 1.55 -1.55)
			(stroke
				(width 0.15)
				(type solid)
			)
			(layer "F.Fab")
		)
		(fp_line
			(start 1.55 -1.55)
			(end 1.55 1.55)
			(stroke
				(width 0.15)
				(type solid)
			)
			(layer "F.Fab")
		)
		(fp_text user "License: Apache-2.0"
			(at -2 6.5 270)
			(layer "F.Fab")
			(effects
				(font
					(size 0.7 0.7)
					(thickness 0.15)
				)
				(justify left bottom)
			)
		)
		(fp_text user "${REFERENCE}"
			(at -1.9 2.9 270)
			(layer "F.Fab")
			(effects
				(font
					(size 0.7 0.7)
					(thickness 0.15)
				)
				(justify left bottom)
			)
		)
		(fp_text user "Author: Antmicro"
			(at -2 5.3 270)
			(layer "F.Fab")
			(effects
				(font
					(size 0.7 0.7)
					(thickness 0.15)
				)
				(justify left bottom)
			)
		)
		(pad "1" smd roundrect
			(at -1.485 -0.95 270)
			(size 0.76 0.42)
			(layers "F.Cu" "F.Mask" "F.Paste")
			(roundrect_rratio 0.125)
			(net 1383 "VCC_NO_OVP")
			(pinfunction "VCC")
			(pintype "power_in")
			(solder_mask_margin 0)
		)
		(pad "2" smd roundrect
			(at -1.485 0 270)
			(size 0.76 0.42)
			(layers "F.Cu" "F.Mask" "F.Paste")
			(roundrect_rratio 0.125)
			(net 1 "GND")
			(pinfunction "GND")
			(pintype "power_in")
		)
		(pad "3" smd roundrect
			(at -1.485 0.95 270)
			(size 0.76 0.42)
			(layers "F.Cu" "F.Mask" "F.Paste")
			(roundrect_rratio 0.125)
			(net 1385 "Net-(Q41-G)")
			(pinfunction "GATE2")
			(pintype "output")
		)
		(pad "4" smd roundrect
			(at 1.485 0.95 270)
			(size 0.76 0.42)
			(layers "F.Cu" "F.Mask" "F.Paste")
			(roundrect_rratio 0.125)
			(net 1386 "Net-(U9-SET)")
			(pinfunction "SET")
			(pintype "input")
		)
		(pad "5" smd roundrect
			(at 1.485 0 270)
			(size 0.76 0.42)
			(layers "F.Cu" "F.Mask" "F.Paste")
			(roundrect_rratio 0.125)
			(net 1383 "VCC_NO_OVP")
			(pinfunction "EN")
			(pintype "input")
		)
		(pad "6" smd roundrect
			(at 1.485 -0.95 270)
			(size 0.76 0.42)
			(layers "F.Cu" "F.Mask" "F.Paste")
			(roundrect_rratio 0.125)
			(net 1384 "Net-(Q32-G)")
			(pinfunction "GATE1")
			(pintype "output")
		)
		(pad "7" smd rect
			(at 0 0 270)
			(size 1.5 2.3)
			(layers "F.Cu" "F.Mask")
			(net 1 "GND")
			(pinfunction "GND")
			(pintype "power_in")
		)
	)
	(footprint "antmicro-footprints:USON-10_2.5x1mm_P0.5mm"
		(layer "F.Cu")
		(at 221.402132 96.162)
		(descr "USON-10 2.5x1mm_ Pitch 0.5mm")
		(tags "USON-10 2.5x1mm Pitch 0.5mm")
		(property "Reference" "U36"
			(at 1.9 1.12 90)
			(layer "F.SilkS")
			(effects
				(font
					(size 0.7 0.7)
					(thickness 0.15)
				)
				(justify left bottom)
			)
		)
		(property "Value" "TPD4E05U06QDQARQ1"
			(at 0.018 2.499 0)
			(layer "F.Fab")
			(effects
				(font
					(size 0.7 0.7)
					(thickness 0.15)
				)
				(justify left bottom)
			)
		)
		(property "Datasheet" "https://www.ti.com/lit/ds/symlink/tpd4e05u06-q1.pdf?HQS=dis-mous-null-mousermode-dsf-pf-null-wwe&ts=1663591265741&ref_url=https%253A%252F%252Fwww.mouser.com%252F"
			(at 0 0 0)
			(layer "F.Fab")
			(hide yes)
			(effects
				(font
					(size 1.27 1.27)
					(thickness 0.15)
				)
			)
		)
		(property "Description" "TVS diode array, 12 kV, USON-10, 5.5 V, 0.5 pF"
			(at 0 0 0)
			(layer "F.Fab")
			(hide yes)
			(effects
				(font
					(size 1.27 1.27)
					(thickness 0.15)
				)
			)
		)
		(property "Manufacturer" "Texas Instruments"
			(at 0 0 0)
			(unlocked yes)
			(layer "F.Fab")
			(hide yes)
			(effects
				(font
					(size 1 1)
					(thickness 0.15)
				)
			)
		)
		(property "MPN" "TPD4E05U06QDQARQ1"
			(at 0 0 0)
			(unlocked yes)
			(layer "F.Fab")
			(hide yes)
			(effects
				(font
					(size 1 1)
					(thickness 0.15)
				)
			)
		)
		(property "Author" "Antmicro"
			(at 0 0 0)
			(unlocked yes)
			(layer "F.Fab")
			(hide yes)
			(effects
				(font
					(size 1 1)
					(thickness 0.15)
				)
			)
		)
		(property "License" "Apache-2.0"
			(at 0 0 0)
			(unlocked yes)
			(layer "F.Fab")
			(hide yes)
			(effects
				(font
					(size 1 1)
					(thickness 0.15)
				)
			)
		)
		(sheetname "/USB DP Alt mode/")
		(sheetfile "usb_dp.kicad_sch")
		(attr smd)
		(fp_line
			(start 0.498 -1.401)
			(end -0.5 -1.401)
			(stroke
				(width 0.15)
				(type solid)
			)
			(layer "F.SilkS")
		)
		(fp_line
			(start 0.498 1.398)
			(end -0.5 1.398)
			(stroke
				(width 0.15)
				(type solid)
			)
			(layer "F.SilkS")
		)
		(fp_circle
			(center -0.68 -1.27)
			(end -0.63 -1.27)
			(stroke
				(width 0.15)
				(type solid)
			)
			(fill yes)
			(layer "F.SilkS")
		)
		(fp_rect
			(start -0.8 -1.5)
			(end 0.8 1.499)
			(stroke
				(width 0.05)
				(type solid)
			)
			(fill no)
			(layer "F.CrtYd")
		)
		(fp_line
			(start -0.5 -1)
			(end -0.5 1.249)
			(stroke
				(width 0.15)
				(type solid)
			)
			(layer "F.Fab")
		)
		(fp_line
			(start -0.5 1.249)
			(end 0.498 1.249)
			(stroke
				(width 0.15)
				(type solid)
			)
			(layer "F.Fab")
		)
		(fp_line
			(start -0.25 -1.25)
			(end -0.5 -1)
			(stroke
				(width 0.15)
				(type solid)
			)
			(layer "F.Fab")
		)
		(fp_line
			(start 0.498 -1.25)
			(end -0.25 -1.25)
			(stroke
				(width 0.15)
				(type solid)
			)
			(layer "F.Fab")
		)
		(fp_line
			(start 0.498 -1.25)
			(end 0.498 1.249)
			(stroke
				(width 0.15)
				(type solid)
			)
			(layer "F.Fab")
		)
		(fp_text user "${REFERENCE}"
			(at -0.802 4.498 0)
			(layer "F.Fab")
			(effects
				(font
					(size 0.7 0.7)
					(thickness 0.15)
				)
				(justify left bottom)
			)
		)
		(fp_text user "Author: Antmicro"
			(at -0.802 5.7 0)
			(layer "F.Fab")
			(effects
				(font
					(size 0.7 0.7)
					(thickness 0.15)
				)
				(justify left bottom)
			)
		)
		(fp_text user "License: Apache-2.0"
			(at -0.802 6.9 0)
			(layer "F.Fab")
			(effects
				(font
					(size 0.7 0.7)
					(thickness 0.15)
				)
				(justify left bottom)
			)
		)
		(pad "1" smd roundrect
			(at -0.387 -1 270)
			(size 0.25 0.55)
			(layers "F.Cu" "F.Mask" "F.Paste")
			(roundrect_rratio 0.25)
			(net 821 "/USB DP Alt mode/USBC1_SBU_N")
			(pintype "passive")
		)
		(pad "2" smd roundrect
			(at -0.387 -0.5 270)
			(size 0.25 0.55)
			(layers "F.Cu" "F.Mask" "F.Paste")
			(roundrect_rratio 0.25)
			(net 815 "/USB DP Alt mode/USBC1_SBU_P")
			(pintype "passive")
		)
		(pad "3" smd roundrect
			(at -0.387 0 270)
			(size 0.4 0.55)
			(layers "F.Cu" "F.Mask" "F.Paste")
			(roundrect_rratio 0.25)
			(net 1 "GND")
			(pintype "power_in")
		)
		(pad "4" smd roundrect
			(at -0.387 0.498 270)
			(size 0.25 0.55)
			(layers "F.Cu" "F.Mask" "F.Paste")
			(roundrect_rratio 0.25)
			(net 1116 "unconnected-(U36-Pad4)")
			(pintype "passive+no_connect")
		)
		(pad "5" smd roundrect
			(at -0.387 0.998 270)
			(size 0.25 0.55)
			(layers "F.Cu" "F.Mask" "F.Paste")
			(roundrect_rratio 0.25)
			(net 1117 "unconnected-(U36-Pad5)")
			(pintype "passive+no_connect")
		)
		(pad "6" smd roundrect
			(at 0.385 0.998 270)
			(size 0.25 0.55)
			(layers "F.Cu" "F.Mask" "F.Paste")
			(roundrect_rratio 0.25)
			(net 1119 "unconnected-(U36-Pad5)_1")
			(pintype "passive+no_connect")
		)
		(pad "7" smd roundrect
			(at 0.385 0.498 270)
			(size 0.25 0.55)
			(layers "F.Cu" "F.Mask" "F.Paste")
			(roundrect_rratio 0.25)
			(net 1118 "unconnected-(U36-Pad4)_1")
			(pintype "passive+no_connect")
		)
		(pad "8" smd roundrect
			(at 0.385 0 270)
			(size 0.4 0.55)
			(layers "F.Cu" "F.Mask" "F.Paste")
			(roundrect_rratio 0.25)
			(net 1 "GND")
			(pintype "passive")
		)
		(pad "9" smd roundrect
			(at 0.385 -0.5 270)
			(size 0.25 0.55)
			(layers "F.Cu" "F.Mask" "F.Paste")
			(roundrect_rratio 0.25)
			(net 815 "/USB DP Alt mode/USBC1_SBU_P")
			(pintype "passive")
		)
		(pad "10" smd roundrect
			(at 0.385 -1 270)
			(size 0.25 0.55)
			(layers "F.Cu" "F.Mask" "F.Paste")
			(roundrect_rratio 0.25)
			(net 821 "/USB DP Alt mode/USBC1_SBU_N")
			(pintype "passive")
		)
	)
)
